FILE_TYPE = CONNECTIVITY;
{Allegro Design Entry HDL 17.4-2019 S026 (4007227) 1/17/2022}
"PAGE_NUMBER" = 11;
0"NC";
1"M_B_CPU0_SB_CA<6:0>";
2"M_B_CPU0_SB_DQS_DP<9:0>";
3"M_B_CPU0_SB_DQS_DN<9:0>";
4"M_B_CPU0_SA_CA<6:0>";
5"M_B_CPU0_SA_DQS_DP<9:0>";
6"M_B_CPU0_SA_DQS_DN<9:0>";
7"M_B_CPU0_SB_CB<7:0>";
8"M_B_CPU0_SA_CB<7:0>";
9"M_B_CPU0_SB_DQ<31:0>";
10"M_B_CPU0_SA_DQ<31:0>";
11"M_B_CPU0_SA_DQ<11>";
12"M_B_CPU0_SA_DQ<12>";
13"M_B_CPU0_SA_DQ<13>";
14"M_B_CPU0_SA_DQ<0>";
15"M_B_CPU0_SA_DQ<14>";
16"M_B_CPU0_SA_DQ<1>";
17"M_B_CPU0_SA_DQ<2>";
18"M_B_CPU0_SA_DQ<3>";
19"M_B_CPU0_SA_DQ<4>";
20"M_B_CPU0_SA_DQ<5>";
21"M_B_CPU0_SA_DQ<6>";
22"M_B_CPU0_SA_DQ<7>";
23"M_B_CPU0_SA_DQ<8>";
24"M_B_CPU0_SA_DQ<9>";
25"M_B_CPU0_SA_DQ<10>";
26"M_B_CPU0_SA_DQ<22>";
27"M_B_CPU0_SA_DQ<23>";
28"M_B_CPU0_SA_DQ<25>";
29"M_B_CPU0_SA_DQ<26>";
30"M_B_CPU0_SA_DQ<15>";
31"M_B_CPU0_SA_DQ<27>";
32"M_B_CPU0_SA_DQ<16>";
33"M_B_CPU0_SA_DQ<28>";
34"M_B_CPU0_SA_DQ<17>";
35"M_B_CPU0_SA_DQ<29>";
36"M_B_CPU0_SA_DQ<18>";
37"M_B_CPU0_SA_DQ<19>";
38"M_B_CPU0_SA_DQ<30>";
39"M_B_CPU0_SA_DQ<31>";
40"M_B_CPU0_SA_DQ<20>";
41"M_B_CPU0_SA_DQ<21>";
42"M_B_CPU0_SA_DQ<24>";
43"M_B_CPU0_SB_DQ<0>";
44"M_B_CPU0_SB_DQ<1>";
45"M_B_CPU0_SB_DQ<10>";
46"M_B_CPU0_SB_DQ<2>";
47"M_B_CPU0_SB_DQ<11>";
48"M_B_CPU0_SB_DQ<3>";
49"M_B_CPU0_SB_DQ<12>";
50"M_B_CPU0_SB_DQ<4>";
51"M_B_CPU0_SB_DQ<13>";
52"M_B_CPU0_SB_DQ<5>";
53"M_B_CPU0_SB_DQ<14>";
54"M_B_CPU0_SB_DQ<6>";
55"M_B_CPU0_SB_DQ<15>";
56"M_B_CPU0_SB_DQ<7>";
57"M_B_CPU0_SB_DQ<16>";
58"M_B_CPU0_SB_DQ<8>";
59"M_B_CPU0_SB_DQ<17>";
60"M_B_CPU0_SB_DQ<9>";
61"M_B_CPU0_SB_DQ<18>";
62"M_B_CPU0_SA_CB<2>";
63"M_B_CPU0_SA_CB<3>";
64"M_B_CPU0_SA_CB<4>";
65"M_B_CPU0_SB_DQ<30>";
66"M_B_CPU0_SB_DQ<31>";
67"M_B_CPU0_SB_DQ<21>";
68"M_B_CPU0_SB_DQ<22>";
69"M_B_CPU0_SB_DQ<23>";
70"M_B_CPU0_SB_DQ<24>";
71"M_B_CPU0_SB_DQ<25>";
72"M_B_CPU0_SB_DQ<26>";
73"M_B_CPU0_SB_DQ<27>";
74"M_B_CPU0_SB_DQ<28>";
75"M_B_CPU0_SB_DQ<29>";
76"M_B_CPU0_SA_CB<0>";
77"M_B_CPU0_SA_CB<1>";
78"M_B_CPU0_SB_DQ<19>";
79"M_B_CPU0_SB_DQ<20>";
80"M_B_CPU0_SA_CB<5>";
81"M_B_CPU0_SB_CB<0>";
82"M_B_CPU0_SA_CB<6>";
83"M_B_CPU0_SB_CB<1>";
84"M_B_CPU0_SA_CB<7>";
85"M_B_CPU0_SB_CB<2>";
86"M_B_CPU0_SB_CB<3>";
87"M_B_CPU0_SB_CB<4>";
88"M_B_CPU0_SB_CB<5>";
89"M_B_CPU0_SB_CB<6>";
90"M_B_CPU0_SB_CB<7>";
91"M_B_CPU0_SA_DQS_DN<0>";
92"M_B_CPU0_SA_DQS_DN<1>";
93"M_B_CPU0_SA_DQS_DN<2>";
94"M_B_CPU0_SA_DQS_DN<3>";
95"M_B_CPU0_SA_DQS_DN<4>";
96"M_B_CPU0_SA_DQS_DP<0>";
97"M_B_CPU0_SA_DQS_DN<5>";
98"M_B_CPU0_SA_DQS_DP<1>";
99"M_B_CPU0_SA_DQS_DN<6>";
100"M_B_CPU0_SA_DQS_DP<2>";
101"M_B_CPU0_SA_DQS_DN<7>";
102"M_B_CPU0_SA_DQS_DP<3>";
103"M_B_CPU0_SA_DQS_DP<4>";
104"M_B_CPU0_SA_DQS_DP<5>";
105"M_B_CPU0_SA_DQS_DP<6>";
106"M_B_CPU0_SA_DQS_DP<7>";
107"M_B_CPU0_SB_DQS_DP<5>";
108"M_B_CPU0_SB_DQS_DP<6>";
109"M_B_CPU0_SB_DQS_DP<7>";
110"M_B_CPU0_SB_DQS_DN<0>";
111"M_B_CPU0_SB_DQS_DN<1>";
112"M_B_CPU0_SB_DQS_DN<2>";
113"M_B_CPU0_SA_DQS_DN<8>";
114"M_B_CPU0_SB_DQS_DN<3>";
115"M_B_CPU0_SA_DQS_DN<9>";
116"M_B_CPU0_SB_DQS_DN<4>";
117"M_B_CPU0_SB_DQS_DP<0>";
118"M_B_CPU0_SB_DQS_DN<5>";
119"M_B_CPU0_SB_DQS_DP<1>";
120"M_B_CPU0_SB_DQS_DN<6>";
121"M_B_CPU0_SB_DQS_DP<2>";
122"M_B_CPU0_SA_DQS_DP<8>";
123"M_B_CPU0_SB_DQS_DP<3>";
124"M_B_CPU0_SA_DQS_DP<9>";
125"M_B_CPU0_SB_DQS_DP<4>";
126"M_B_CPU0_SB_DQS_DN<9>";
127"M_B_CPU0_SB_DQS_DP<8>";
128"M_B_CPU0_SA_CA<0>";
129"M_B_CPU0_SB_CA<0>";
130"M_B_CPU0_SA_CA<1>";
131"M_B_CPU0_SB_CA<1>";
132"M_B_CPU0_SA_CA<2>";
133"M_B_CPU0_SB_CA<2>";
134"M_B_CPU0_SA_CA<3>";
135"M_B_CPU0_SB_CA<3>";
136"M_B_CPU0_SA_CA<4>";
137"M_B_CPU0_SB_CA<4>";
138"M_B_CPU0_SA_CA<5>";
139"M_B_CPU0_SB_CA<5>";
140"M_B_CPU0_SA_CA<6>";
141"M_B_CPU0_SB_DQS_DN<7>";
142"M_B_CPU0_SB_DQS_DN<8>";
143"M_B_CPU0_SB_DQS_DP<9>";
144"M_B_CPU0_SB_CA<6>";
145"M_B_CPU0_RESET_N";
146"M_B_CPU0_SB_RSP<0>";
147"M_B_CPU0_SB_PAR";
148"M_B_CPU0_SB_CS_N<1>";
149"M_B_CPU0_SB_CS_N<0>";
150"M_B_CPU0_SA_PAR";
151"M_B_CPU0_SA_CS_N<1>";
152"M_B_CPU0_SA_CS_N<0>";
153"M_B_CPU0_CLK_DN<0>";
154"M_B_CPU0_CLK_DP<0>";
155"TP_M_B_CPU0_SA_TEST39B";
156"M_B_CPU0_ALERT_N";
157"M_B_CPU0_ALERT_R_N";
158"M_B_CPU0_SA_RSP<0>";
%"GENOA_SP5"
"2","(-4550,3475)","0","pure_quanta","I171";
;
LOCATION"U25"
$SEC"2"
CDS_SEC"2"
PART_TYPE"SMLF"
MATERIAL"IO"
VALUE"SOCKET6096_13568-001"
CDS_LMAN_SYM_OUTLINE"-650,2550,650,-2550"
CDS_LIB"pure_quanta"
NEEDS_NO_SIZE"TRUE"
PART_NUMBER"DGA^6000030";
"TEST39B"
$PN"BF62"155;
"MBB_DATA20"
$PN"CV63"79;
"MBA_DATA24"
$PN"AC64"42;
"MBB_DATA19"
$PN"CT62"78;
"MB1_CLK_L"
$PN"BG64"0;
"MB1_CLK_H"
$PN"BF63"0;
"MB0_CLK_L"
$PN"BD63"153;
"MB0_CLK_H"
$PN"BC64"154;
"MBB_PAR"
$PN"BL64"147;
"MBA_PAR"
$PN"BC62"150;
"MBB_DQS_H9"
$PN"BV63"143;
"MBA_CHECK1"
$PN"AK62"77;
"MBA_DATA10"
$PN"M63"25;
"MBA_DATA21"
$PN"AB62"41;
"MBB_DQS_H4"
$PN"BY62"125;
"MBB_DQS_L8"
$PN"DC62"142;
"MBA1_CS_L1"
$PN"AV62"0;
"MBA_CHECK0"
$PN"AJ64"76;
"MBA_DATA20"
$PN"AA64"40;
"MBA_DATA31"
$PN"AJ62"39;
"MBA_DQS_H9"
$PN"AN62"124;
"MBB_CA6"
$PN"BK63"144;
"MBB_DQS_H3"
$PN"DB63"123;
"MBB_DQS_L7"
$PN"CU62"141;
"MBA0_CS_L1"
$PN"AW62"151;
"MBA1_CS_L0"
$PN"AU64"0;
"MBA_CA6"
$PN"BB62"140;
"MBA_DATA30"
$PN"AH63"38;
"MBA_DQS_H8"
$PN"AG62"122;
"MBB_CA5"
$PN"BK62"139;
"MBB_DQS_H2"
$PN"CT63"121;
"MBB_DQS_L6"
$PN"CL62"120;
"MBA0_CS_L0"
$PN"AV63"152;
"MBA_CA5"
$PN"BB63"138;
"MBA_DQS_H7"
$PN"AA62"106;
"MBB_CA4"
$PN"BJ62"137;
"MBB_DATA18"
$PN"CR64"61;
"MBB_DATA29"
$PN"DE62"75;
"MBB_DQS_H1"
$PN"CK63"119;
"MBB_DQS_L5"
$PN"CE62"118;
"MBA_CA4"
$PN"BA64"136;
"MBA_DQS_H6"
$PN"R62"105;
"MBB1_RSP_L"
$PN"BR64"0;
"MBB_CA3"
$PN"BJ64"135;
"MBB_DATA9"
$PN"CJ62"60;
"MBB_DATA17"
$PN"CR62"59;
"MBB_DATA28"
$PN"DD63"74;
"MBB_DQS_H0"
$PN"CD63"117;
"MBB_DQS_L4"
$PN"BW62"116;
"MBA_CA3"
$PN"BA62"134;
"MBA_DATA9"
$PN"M62"24;
"MBA_DQS_H5"
$PN"J62"104;
"MBA_DQS_L9"
$PN"AM62"115;
"MBB0_RSP_L"
$PN"BP63"146;
"MBB_CA2"
$PN"BH63"133;
"MBB_CHECK7"
$PN"BV62"90;
"MBB_DATA8"
$PN"CH63"58;
"MBB_DATA16"
$PN"CP63"57;
"MBB_DATA27"
$PN"DB62"73;
"MBB_DQS_L3"
$PN"DC64"114;
"MBA_CA2"
$PN"AY62"132;
"MBA_DATA8"
$PN"L64"23;
"MBA_DQS_H4"
$PN"AL64"103;
"MBA_DQS_L8"
$PN"AF62"113;
"MBB_CA1"
$PN"BH62"131;
"MBB_CHECK6"
$PN"BU64"89;
"MBB_DATA7"
$PN"CH62"56;
"MBB_DATA15"
$PN"CP62"55;
"MBB_DATA26"
$PN"DA64"72;
"MBB_DQS_L2"
$PN"CU64"112;
"MBA_CA1"
$PN"AY63"130;
"MBA_DATA7"
$PN"L62"22;
"MBA_DQS_H3"
$PN"AE64"102;
"MBA_DQS_L7"
$PN"Y62"101;
"MBB_CA0"
$PN"BG62"129;
"MBB_CHECK5"
$PN"BU62"88;
"MBB_DATA6"
$PN"CG64"54;
"MBB_DATA14"
$PN"CN64"53;
"MBB_DATA25"
$PN"DA62"71;
"MBB_DQS_L1"
$PN"CL64"111;
"MBA_CA0"
$PN"AW64"128;
"MBA_DATA6"
$PN"K63"21;
"MBA_DATA19"
$PN"W62"37;
"MBA_DQS_H2"
$PN"W64"100;
"MBA_DQS_L6"
$PN"P62"99;
"MBB_CHECK4"
$PN"BT63"87;
"MBB_DATA5"
$PN"CG62"52;
"MBB_DATA13"
$PN"CN62"51;
"MBB_DATA24"
$PN"CY63"70;
"MBB_DQS_L0"
$PN"CE64"110;
"MBA_DATA5"
$PN"K62"20;
"MBA_DATA18"
$PN"V63"36;
"MBA_DATA29"
$PN"AH62"35;
"MBA_DQS_H1"
$PN"N64"98;
"MBA_DQS_L5"
$PN"H62"97;
"MBB_CHECK3"
$PN"CB62"86;
"MBB_DATA4"
$PN"CF63"50;
"MBB_DATA12"
$PN"CM63"49;
"MBB_DATA23"
$PN"CY62"69;
"MBA1_RSP_L"
$PN"BP62"0;
"MBA_DATA4"
$PN"J64"19;
"MBA_DATA17"
$PN"V62"34;
"MBA_DATA28"
$PN"AG64"33;
"MBA_DQS_H0"
$PN"G64"96;
"MBA_DQS_L4"
$PN"AM63"95;
"MBB_CHECK2"
$PN"CA64"85;
"MBB_DATA3"
$PN"CD62"48;
"MBB_DATA11"
$PN"CK62"47;
"MBB_DATA22"
$PN"CW64"68;
"MBA0_RSP_L"
$PN"BN62"158;
"MBA_CHECK7"
$PN"AR62"84;
"MBA_DATA3"
$PN"G62"18;
"MBA_DATA16"
$PN"U64"32;
"MBA_DATA27"
$PN"AE62"31;
"MBA_DQS_L3"
$PN"AF63"94;
"MBB_CHECK1"
$PN"CA62"83;
"MBB_DATA2"
$PN"CC64"46;
"MBB_DATA10"
$PN"CJ64"45;
"MBB_DATA21"
$PN"CW62"67;
"MBA_CHECK6"
$PN"AP63"82;
"MBA_DATA2"
$PN"F63"17;
"MBA_DATA15"
$PN"U62"30;
"MBA_DATA26"
$PN"AD63"29;
"MBA_DQS_L2"
$PN"Y63"93;
"MBB1_CS_L1"
$PN"BM63"0;
"MBB_CHECK0"
$PN"BY63"81;
"MBB_DATA1"
$PN"CC62"44;
"MBB_DATA31"
$PN"DF62"66;
"MBA_CHECK5"
$PN"AP62"80;
"MBA_DATA1"
$PN"F62"16;
"MBA_DATA14"
$PN"T63"15;
"MBA_DATA25"
$PN"AD62"28;
"MBA_DQS_L1"
$PN"P63"92;
"MBB0_CS_L1"
$PN"BN64"148;
"MBB1_CS_L0"
$PN"BL62"0;
"MBB_DATA0"
$PN"CB63"43;
"MBB_DATA30"
$PN"DE64"65;
"MBB_DQS_H8"
$PN"DD62"127;
"MBA_CHECK4"
$PN"AN64"64;
"MBA_DATA0"
$PN"E64"14;
"MBA_DATA13"
$PN"T62"13;
"MBA_DQS_L0"
$PN"H63"91;
"MBB0_CS_L0"
$PN"BM62"149;
"MBB_DQS_H7"
$PN"CV62"109;
"MBA_CHECK3"
$PN"AL62"63;
"MBA_DATA12"
$PN"R64"12;
"MBA_DATA23"
$PN"AC62"27;
"MBB_DQS_H6"
$PN"CM62"108;
"MBA_CHECK2"
$PN"AK63"62;
"MBA_DATA11"
$PN"N62"11;
"MBA_DATA22"
$PN"AB63"26;
"MBB_DQS_H5"
$PN"CF62"107;
"MBB_DQS_L9"
$PN"BW64"126;
"MB_RESET_L"
$PN"AU62"145;
"MB_ALERT_L"
$PN"AT62"157;
%"TAP"
"1","(-3275,5775)","0","mstr_standard","I173";
;
CDS_LIB"mstr_standard"
BODY_TYPE"PLUMBING"
HDL_TAP"TRUE";
"B \NAC \NWC"10;
"S \NAC"
BN"2"17;
%"TAP"
"1","(-3275,5825)","0","mstr_standard","I174";
;
CDS_LIB"mstr_standard"
BODY_TYPE"PLUMBING"
HDL_TAP"TRUE";
"B \NAC \NWC"10;
"S \NAC"
BN"1"16;
%"TAP"
"1","(-3275,5875)","0","mstr_standard","I175";
;
CDS_LIB"mstr_standard"
BODY_TYPE"PLUMBING"
HDL_TAP"TRUE";
"B \NAC \NWC"10;
"S \NAC"
BN"0"14;
%"TAP"
"1","(-3275,5675)","0","mstr_standard","I176";
;
CDS_LIB"mstr_standard"
BODY_TYPE"PLUMBING"
HDL_TAP"TRUE";
"B \NAC \NWC"10;
"S \NAC"
BN"4"19;
%"TAP"
"1","(-3275,5725)","0","mstr_standard","I177";
;
CDS_LIB"mstr_standard"
BODY_TYPE"PLUMBING"
HDL_TAP"TRUE";
"B \NAC \NWC"10;
"S \NAC"
BN"3"18;
%"TAP"
"1","(-3275,5625)","0","mstr_standard","I178";
;
CDS_LIB"mstr_standard"
BODY_TYPE"PLUMBING"
HDL_TAP"TRUE";
"B \NAC \NWC"10;
"S \NAC"
BN"5"20;
%"TAP"
"1","(-3275,5575)","0","mstr_standard","I179";
;
CDS_LIB"mstr_standard"
BODY_TYPE"PLUMBING"
HDL_TAP"TRUE";
"B \NAC \NWC"10;
"S \NAC"
BN"6"21;
%"TAP"
"1","(-3275,5525)","0","mstr_standard","I180";
;
CDS_LIB"mstr_standard"
BODY_TYPE"PLUMBING"
HDL_TAP"TRUE";
"B \NAC \NWC"10;
"S \NAC"
BN"7"22;
%"TAP"
"1","(-3275,5425)","0","mstr_standard","I181";
;
CDS_LIB"mstr_standard"
BODY_TYPE"PLUMBING"
HDL_TAP"TRUE";
"B \NAC \NWC"10;
"S \NAC"
BN"8"23;
%"TAP"
"1","(-3275,5275)","0","mstr_standard","I182";
;
CDS_LIB"mstr_standard"
BODY_TYPE"PLUMBING"
HDL_TAP"TRUE";
"B \NAC \NWC"10;
"S \NAC"
BN"11"11;
%"TAP"
"1","(-3275,5325)","0","mstr_standard","I183";
;
CDS_LIB"mstr_standard"
BODY_TYPE"PLUMBING"
HDL_TAP"TRUE";
"B \NAC \NWC"10;
"S \NAC"
BN"10"25;
%"TAP"
"1","(-3275,5375)","0","mstr_standard","I184";
;
CDS_LIB"mstr_standard"
BODY_TYPE"PLUMBING"
HDL_TAP"TRUE";
"B \NAC \NWC"10;
"S \NAC"
BN"9"24;
%"TAP"
"1","(-3275,5225)","0","mstr_standard","I185";
;
CDS_LIB"mstr_standard"
BODY_TYPE"PLUMBING"
HDL_TAP"TRUE";
"B \NAC \NWC"10;
"S \NAC"
BN"12"12;
%"TAP"
"1","(-3275,5175)","0","mstr_standard","I186";
;
CDS_LIB"mstr_standard"
BODY_TYPE"PLUMBING"
HDL_TAP"TRUE";
"B \NAC \NWC"10;
"S \NAC"
BN"13"13;
%"TAP"
"1","(-3275,5125)","0","mstr_standard","I187";
;
CDS_LIB"mstr_standard"
BODY_TYPE"PLUMBING"
HDL_TAP"TRUE";
"B \NAC \NWC"10;
"S \NAC"
BN"14"15;
%"TAP"
"1","(-3275,5075)","0","mstr_standard","I188";
;
CDS_LIB"mstr_standard"
BODY_TYPE"PLUMBING"
HDL_TAP"TRUE";
"B \NAC \NWC"10;
"S \NAC"
BN"15"30;
%"TAP"
"1","(-3275,4975)","0","mstr_standard","I189";
;
CDS_LIB"mstr_standard"
BODY_TYPE"PLUMBING"
HDL_TAP"TRUE";
"B \NAC \NWC"10;
"S \NAC"
BN"16"32;
%"TAP"
"1","(-3275,4925)","0","mstr_standard","I190";
;
CDS_LIB"mstr_standard"
BODY_TYPE"PLUMBING"
HDL_TAP"TRUE";
"B \NAC \NWC"10;
"S \NAC"
BN"17"34;
%"TAP"
"1","(-3275,4875)","0","mstr_standard","I191";
;
CDS_LIB"mstr_standard"
BODY_TYPE"PLUMBING"
HDL_TAP"TRUE";
"B \NAC \NWC"10;
"S \NAC"
BN"18"36;
%"TAP"
"1","(-3275,4775)","0","mstr_standard","I192";
;
CDS_LIB"mstr_standard"
BODY_TYPE"PLUMBING"
HDL_TAP"TRUE";
"B \NAC \NWC"10;
"S \NAC"
BN"20"40;
%"TAP"
"1","(-3275,4825)","0","mstr_standard","I193";
;
CDS_LIB"mstr_standard"
BODY_TYPE"PLUMBING"
HDL_TAP"TRUE";
"B \NAC \NWC"10;
"S \NAC"
BN"19"37;
%"TAP"
"1","(-3275,4725)","0","mstr_standard","I194";
;
CDS_LIB"mstr_standard"
BODY_TYPE"PLUMBING"
HDL_TAP"TRUE";
"B \NAC \NWC"10;
"S \NAC"
BN"21"41;
%"TAP"
"1","(-3275,4675)","0","mstr_standard","I195";
;
CDS_LIB"mstr_standard"
BODY_TYPE"PLUMBING"
HDL_TAP"TRUE";
"B \NAC \NWC"10;
"S \NAC"
BN"22"26;
%"TAP"
"1","(-3275,4625)","0","mstr_standard","I196";
;
CDS_LIB"mstr_standard"
BODY_TYPE"PLUMBING"
HDL_TAP"TRUE";
"B \NAC \NWC"10;
"S \NAC"
BN"23"27;
%"TAP"
"1","(-3275,4525)","0","mstr_standard","I197";
;
CDS_LIB"mstr_standard"
BODY_TYPE"PLUMBING"
HDL_TAP"TRUE";
"B \NAC \NWC"10;
"S \NAC"
BN"24"42;
%"TAP"
"1","(-3275,4475)","0","mstr_standard","I198";
;
CDS_LIB"mstr_standard"
BODY_TYPE"PLUMBING"
HDL_TAP"TRUE";
"B \NAC \NWC"10;
"S \NAC"
BN"25"28;
%"TAP"
"1","(-3275,4425)","0","mstr_standard","I199";
;
CDS_LIB"mstr_standard"
BODY_TYPE"PLUMBING"
HDL_TAP"TRUE";
"B \NAC \NWC"10;
"S \NAC"
BN"26"29;
%"TAP"
"1","(-3275,4375)","0","mstr_standard","I200";
;
CDS_LIB"mstr_standard"
BODY_TYPE"PLUMBING"
HDL_TAP"TRUE";
"B \NAC \NWC"10;
"S \NAC"
BN"27"31;
%"TAP"
"1","(-3275,4275)","0","mstr_standard","I201";
;
CDS_LIB"mstr_standard"
BODY_TYPE"PLUMBING"
HDL_TAP"TRUE";
"B \NAC \NWC"10;
"S \NAC"
BN"29"35;
%"TAP"
"1","(-3275,4225)","0","mstr_standard","I202";
;
CDS_LIB"mstr_standard"
BODY_TYPE"PLUMBING"
HDL_TAP"TRUE";
"B \NAC \NWC"10;
"S \NAC"
BN"30"38;
%"TAP"
"1","(-3275,4325)","0","mstr_standard","I203";
;
CDS_LIB"mstr_standard"
BODY_TYPE"PLUMBING"
HDL_TAP"TRUE";
"B \NAC \NWC"10;
"S \NAC"
BN"28"33;
%"TAP"
"1","(-3275,4175)","0","mstr_standard","I204";
;
CDS_LIB"mstr_standard"
BODY_TYPE"PLUMBING"
HDL_TAP"TRUE";
"B \NAC \NWC"10;
"S \NAC"
BN"31"39;
%"TAP"
"1","(-3275,3975)","0","mstr_standard","I207";
;
CDS_LIB"mstr_standard"
BODY_TYPE"PLUMBING"
HDL_TAP"TRUE";
"B \NAC \NWC"9;
"S \NAC"
BN"2"46;
%"TAP"
"1","(-3275,4025)","0","mstr_standard","I208";
;
CDS_LIB"mstr_standard"
BODY_TYPE"PLUMBING"
HDL_TAP"TRUE";
"B \NAC \NWC"9;
"S \NAC"
BN"1"44;
%"TAP"
"1","(-3275,4075)","0","mstr_standard","I209";
;
CDS_LIB"mstr_standard"
BODY_TYPE"PLUMBING"
HDL_TAP"TRUE";
"B \NAC \NWC"9;
"S \NAC"
BN"0"43;
%"TAP"
"1","(-3275,3925)","0","mstr_standard","I210";
;
CDS_LIB"mstr_standard"
BODY_TYPE"PLUMBING"
HDL_TAP"TRUE";
"B \NAC \NWC"9;
"S \NAC"
BN"3"48;
%"TAP"
"1","(-3275,3875)","0","mstr_standard","I211";
;
CDS_LIB"mstr_standard"
BODY_TYPE"PLUMBING"
HDL_TAP"TRUE";
"B \NAC \NWC"9;
"S \NAC"
BN"4"50;
%"TAP"
"1","(-3275,3825)","0","mstr_standard","I212";
;
CDS_LIB"mstr_standard"
BODY_TYPE"PLUMBING"
HDL_TAP"TRUE";
"B \NAC \NWC"9;
"S \NAC"
BN"5"52;
%"TAP"
"1","(-3275,3725)","0","mstr_standard","I213";
;
CDS_LIB"mstr_standard"
BODY_TYPE"PLUMBING"
HDL_TAP"TRUE";
"B \NAC \NWC"9;
"S \NAC"
BN"7"56;
%"TAP"
"1","(-3275,3775)","0","mstr_standard","I214";
;
CDS_LIB"mstr_standard"
BODY_TYPE"PLUMBING"
HDL_TAP"TRUE";
"B \NAC \NWC"9;
"S \NAC"
BN"6"54;
%"TAP"
"1","(-3275,3625)","0","mstr_standard","I215";
;
CDS_LIB"mstr_standard"
BODY_TYPE"PLUMBING"
HDL_TAP"TRUE";
"B \NAC \NWC"9;
"S \NAC"
BN"8"58;
%"TAP"
"1","(-3275,3475)","0","mstr_standard","I216";
;
CDS_LIB"mstr_standard"
BODY_TYPE"PLUMBING"
HDL_TAP"TRUE";
"B \NAC \NWC"9;
"S \NAC"
BN"11"47;
%"TAP"
"1","(-3275,3575)","0","mstr_standard","I217";
;
CDS_LIB"mstr_standard"
BODY_TYPE"PLUMBING"
HDL_TAP"TRUE";
"B \NAC \NWC"9;
"S \NAC"
BN"9"60;
%"TAP"
"1","(-3275,3525)","0","mstr_standard","I218";
;
CDS_LIB"mstr_standard"
BODY_TYPE"PLUMBING"
HDL_TAP"TRUE";
"B \NAC \NWC"9;
"S \NAC"
BN"10"45;
%"TAP"
"1","(-3275,3425)","0","mstr_standard","I219";
;
CDS_LIB"mstr_standard"
BODY_TYPE"PLUMBING"
HDL_TAP"TRUE";
"B \NAC \NWC"9;
"S \NAC"
BN"12"49;
%"TAP"
"1","(-3275,3375)","0","mstr_standard","I220";
;
CDS_LIB"mstr_standard"
BODY_TYPE"PLUMBING"
HDL_TAP"TRUE";
"B \NAC \NWC"9;
"S \NAC"
BN"13"51;
%"TAP"
"1","(-3275,3275)","0","mstr_standard","I221";
;
CDS_LIB"mstr_standard"
BODY_TYPE"PLUMBING"
HDL_TAP"TRUE";
"B \NAC \NWC"9;
"S \NAC"
BN"15"55;
%"TAP"
"1","(-3275,3325)","0","mstr_standard","I222";
;
CDS_LIB"mstr_standard"
BODY_TYPE"PLUMBING"
HDL_TAP"TRUE";
"B \NAC \NWC"9;
"S \NAC"
BN"14"53;
%"TAP"
"1","(-3275,3175)","0","mstr_standard","I223";
;
CDS_LIB"mstr_standard"
BODY_TYPE"PLUMBING"
HDL_TAP"TRUE";
"B \NAC \NWC"9;
"S \NAC"
BN"16"57;
%"TAP"
"1","(-3275,3125)","0","mstr_standard","I224";
;
CDS_LIB"mstr_standard"
BODY_TYPE"PLUMBING"
HDL_TAP"TRUE";
"B \NAC \NWC"9;
"S \NAC"
BN"17"59;
%"TAP"
"1","(-3275,3075)","0","mstr_standard","I225";
;
CDS_LIB"mstr_standard"
BODY_TYPE"PLUMBING"
HDL_TAP"TRUE";
"B \NAC \NWC"9;
"S \NAC"
BN"18"61;
%"TAP"
"1","(-3275,2975)","0","mstr_standard","I226";
;
CDS_LIB"mstr_standard"
BODY_TYPE"PLUMBING"
HDL_TAP"TRUE";
"B \NAC \NWC"9;
"S \NAC"
BN"20"79;
%"TAP"
"1","(-3275,3025)","0","mstr_standard","I227";
;
CDS_LIB"mstr_standard"
BODY_TYPE"PLUMBING"
HDL_TAP"TRUE";
"B \NAC \NWC"9;
"S \NAC"
BN"19"78;
%"TAP"
"1","(-3275,2825)","0","mstr_standard","I228";
;
CDS_LIB"mstr_standard"
BODY_TYPE"PLUMBING"
HDL_TAP"TRUE";
"B \NAC \NWC"9;
"S \NAC"
BN"23"69;
%"TAP"
"1","(-3275,2925)","0","mstr_standard","I229";
;
CDS_LIB"mstr_standard"
BODY_TYPE"PLUMBING"
HDL_TAP"TRUE";
"B \NAC \NWC"9;
"S \NAC"
BN"21"67;
%"TAP"
"1","(-3275,2875)","0","mstr_standard","I230";
;
CDS_LIB"mstr_standard"
BODY_TYPE"PLUMBING"
HDL_TAP"TRUE";
"B \NAC \NWC"9;
"S \NAC"
BN"22"68;
%"TAP"
"1","(-3275,2725)","0","mstr_standard","I231";
;
CDS_LIB"mstr_standard"
BODY_TYPE"PLUMBING"
HDL_TAP"TRUE";
"B \NAC \NWC"9;
"S \NAC"
BN"24"70;
%"TAP"
"1","(-3275,2625)","0","mstr_standard","I232";
;
CDS_LIB"mstr_standard"
BODY_TYPE"PLUMBING"
HDL_TAP"TRUE";
"B \NAC \NWC"9;
"S \NAC"
BN"26"72;
%"TAP"
"1","(-3275,2675)","0","mstr_standard","I233";
;
CDS_LIB"mstr_standard"
BODY_TYPE"PLUMBING"
HDL_TAP"TRUE";
"B \NAC \NWC"9;
"S \NAC"
BN"25"71;
%"TAP"
"1","(-3275,2575)","0","mstr_standard","I234";
;
CDS_LIB"mstr_standard"
BODY_TYPE"PLUMBING"
HDL_TAP"TRUE";
"B \NAC \NWC"9;
"S \NAC"
BN"27"73;
%"TAP"
"1","(-3275,2525)","0","mstr_standard","I235";
;
CDS_LIB"mstr_standard"
BODY_TYPE"PLUMBING"
HDL_TAP"TRUE";
"B \NAC \NWC"9;
"S \NAC"
BN"28"74;
%"TAP"
"1","(-3275,2475)","0","mstr_standard","I236";
;
CDS_LIB"mstr_standard"
BODY_TYPE"PLUMBING"
HDL_TAP"TRUE";
"B \NAC \NWC"9;
"S \NAC"
BN"29"75;
%"TAP"
"1","(-3275,2425)","0","mstr_standard","I237";
;
CDS_LIB"mstr_standard"
BODY_TYPE"PLUMBING"
HDL_TAP"TRUE";
"B \NAC \NWC"9;
"S \NAC"
BN"30"65;
%"TAP"
"1","(-3275,2375)","0","mstr_standard","I238";
;
CDS_LIB"mstr_standard"
BODY_TYPE"PLUMBING"
HDL_TAP"TRUE";
"B \NAC \NWC"9;
"S \NAC"
BN"31"66;
%"TAP"
"1","(-3275,2275)","0","mstr_standard","I239";
;
CDS_LIB"mstr_standard"
BODY_TYPE"PLUMBING"
HDL_TAP"TRUE";
"B \NAC \NWC"8;
"S \NAC"
BN"0"76;
%"TAP"
"1","(-3275,2225)","0","mstr_standard","I240";
;
CDS_LIB"mstr_standard"
BODY_TYPE"PLUMBING"
HDL_TAP"TRUE";
"B \NAC \NWC"8;
"S \NAC"
BN"1"77;
%"TAP"
"1","(-3275,2075)","0","mstr_standard","I241";
;
CDS_LIB"mstr_standard"
BODY_TYPE"PLUMBING"
HDL_TAP"TRUE";
"B \NAC \NWC"8;
"S \NAC"
BN"4"64;
%"TAP"
"1","(-3275,2175)","0","mstr_standard","I242";
;
CDS_LIB"mstr_standard"
BODY_TYPE"PLUMBING"
HDL_TAP"TRUE";
"B \NAC \NWC"8;
"S \NAC"
BN"2"62;
%"TAP"
"1","(-3275,2125)","0","mstr_standard","I243";
;
CDS_LIB"mstr_standard"
BODY_TYPE"PLUMBING"
HDL_TAP"TRUE";
"B \NAC \NWC"8;
"S \NAC"
BN"3"63;
%"TAP"
"1","(-3275,1925)","0","mstr_standard","I245";
;
CDS_LIB"mstr_standard"
BODY_TYPE"PLUMBING"
HDL_TAP"TRUE";
"B \NAC \NWC"8;
"S \NAC"
BN"7"84;
%"TAP"
"1","(-3275,2025)","0","mstr_standard","I246";
;
CDS_LIB"mstr_standard"
BODY_TYPE"PLUMBING"
HDL_TAP"TRUE";
"B \NAC \NWC"8;
"S \NAC"
BN"5"80;
%"TAP"
"1","(-3275,1975)","0","mstr_standard","I247";
;
CDS_LIB"mstr_standard"
BODY_TYPE"PLUMBING"
HDL_TAP"TRUE";
"B \NAC \NWC"8;
"S \NAC"
BN"6"82;
%"TAP"
"1","(-3275,1825)","0","mstr_standard","I248";
;
CDS_LIB"mstr_standard"
BODY_TYPE"PLUMBING"
HDL_TAP"TRUE";
"B \NAC \NWC"7;
"S \NAC"
BN"0"81;
%"TAP"
"1","(-3275,1775)","0","mstr_standard","I249";
;
CDS_LIB"mstr_standard"
BODY_TYPE"PLUMBING"
HDL_TAP"TRUE";
"B \NAC \NWC"7;
"S \NAC"
BN"1"83;
%"TAP"
"1","(-3275,1725)","0","mstr_standard","I250";
;
CDS_LIB"mstr_standard"
BODY_TYPE"PLUMBING"
HDL_TAP"TRUE";
"B \NAC \NWC"7;
"S \NAC"
BN"2"85;
%"TAP"
"1","(-3275,1675)","0","mstr_standard","I251";
;
CDS_LIB"mstr_standard"
BODY_TYPE"PLUMBING"
HDL_TAP"TRUE";
"B \NAC \NWC"7;
"S \NAC"
BN"3"86;
%"TAP"
"1","(-3275,1625)","0","mstr_standard","I252";
;
CDS_LIB"mstr_standard"
BODY_TYPE"PLUMBING"
HDL_TAP"TRUE";
"B \NAC \NWC"7;
"S \NAC"
BN"4"87;
%"TAP"
"1","(-3275,1575)","0","mstr_standard","I253";
;
CDS_LIB"mstr_standard"
BODY_TYPE"PLUMBING"
HDL_TAP"TRUE";
"B \NAC \NWC"7;
"S \NAC"
BN"5"88;
%"TAP"
"1","(-3275,1475)","0","mstr_standard","I254";
;
CDS_LIB"mstr_standard"
BODY_TYPE"PLUMBING"
HDL_TAP"TRUE";
"B \NAC \NWC"7;
"S \NAC"
BN"7"90;
%"TAP"
"1","(-3275,1525)","0","mstr_standard","I255";
;
CDS_LIB"mstr_standard"
BODY_TYPE"PLUMBING"
HDL_TAP"TRUE";
"B \NAC \NWC"7;
"S \NAC"
BN"6"89;
%"TAP"
"1","(-5700,5875)","2","mstr_standard","I256";
;
CDS_LIB"mstr_standard"
BODY_TYPE"PLUMBING"
HDL_TAP"TRUE";
"B \NAC \NWC"5;
"S \NAC"
BN"0"96;
%"TAP"
"1","(-5700,5775)","2","mstr_standard","I257";
;
CDS_LIB"mstr_standard"
BODY_TYPE"PLUMBING"
HDL_TAP"TRUE";
"B \NAC \NWC"5;
"S \NAC"
BN"1"98;
%"TAP"
"1","(-5700,5675)","2","mstr_standard","I258";
;
CDS_LIB"mstr_standard"
BODY_TYPE"PLUMBING"
HDL_TAP"TRUE";
"B \NAC \NWC"5;
"S \NAC"
BN"2"100;
%"TAP"
"1","(-5900,5725)","2","mstr_standard","I259";
;
CDS_LIB"mstr_standard"
BODY_TYPE"PLUMBING"
HDL_TAP"TRUE";
"B \NAC \NWC"6;
"S \NAC"
BN"1"92;
%"TAP"
"1","(-5900,5825)","2","mstr_standard","I260";
;
CDS_LIB"mstr_standard"
BODY_TYPE"PLUMBING"
HDL_TAP"TRUE";
"B \NAC \NWC"6;
"S \NAC"
BN"0"91;
%"TAP"
"1","(-5700,5575)","2","mstr_standard","I261";
;
CDS_LIB"mstr_standard"
BODY_TYPE"PLUMBING"
HDL_TAP"TRUE";
"B \NAC \NWC"5;
"S \NAC"
BN"3"102;
%"TAP"
"1","(-5700,5375)","2","mstr_standard","I262";
;
CDS_LIB"mstr_standard"
BODY_TYPE"PLUMBING"
HDL_TAP"TRUE";
"B \NAC \NWC"5;
"S \NAC"
BN"5"104;
%"TAP"
"1","(-5700,5475)","2","mstr_standard","I263";
;
CDS_LIB"mstr_standard"
BODY_TYPE"PLUMBING"
HDL_TAP"TRUE";
"B \NAC \NWC"5;
"S \NAC"
BN"4"103;
%"TAP"
"1","(-5900,5425)","2","mstr_standard","I264";
;
CDS_LIB"mstr_standard"
BODY_TYPE"PLUMBING"
HDL_TAP"TRUE";
"B \NAC \NWC"6;
"S \NAC"
BN"4"95;
%"TAP"
"1","(-5900,5625)","2","mstr_standard","I265";
;
CDS_LIB"mstr_standard"
BODY_TYPE"PLUMBING"
HDL_TAP"TRUE";
"B \NAC \NWC"6;
"S \NAC"
BN"2"93;
%"TAP"
"1","(-5900,5525)","2","mstr_standard","I266";
;
CDS_LIB"mstr_standard"
BODY_TYPE"PLUMBING"
HDL_TAP"TRUE";
"B \NAC \NWC"6;
"S \NAC"
BN"3"94;
%"TAP"
"1","(-5700,5175)","2","mstr_standard","I267";
;
CDS_LIB"mstr_standard"
BODY_TYPE"PLUMBING"
HDL_TAP"TRUE";
"B \NAC \NWC"5;
"S \NAC"
BN"7"106;
%"TAP"
"1","(-5700,5275)","2","mstr_standard","I268";
;
CDS_LIB"mstr_standard"
BODY_TYPE"PLUMBING"
HDL_TAP"TRUE";
"B \NAC \NWC"5;
"S \NAC"
BN"6"105;
%"TAP"
"1","(-5900,5325)","2","mstr_standard","I269";
;
CDS_LIB"mstr_standard"
BODY_TYPE"PLUMBING"
HDL_TAP"TRUE";
"B \NAC \NWC"6;
"S \NAC"
BN"5"97;
%"TAP"
"1","(-5900,5225)","2","mstr_standard","I270";
;
CDS_LIB"mstr_standard"
BODY_TYPE"PLUMBING"
HDL_TAP"TRUE";
"B \NAC \NWC"6;
"S \NAC"
BN"6"99;
%"TAP"
"1","(-5900,5125)","2","mstr_standard","I271";
;
CDS_LIB"mstr_standard"
BODY_TYPE"PLUMBING"
HDL_TAP"TRUE";
"B \NAC \NWC"6;
"S \NAC"
BN"7"101;
%"TAP"
"1","(-5700,4975)","2","mstr_standard","I272";
;
CDS_LIB"mstr_standard"
BODY_TYPE"PLUMBING"
HDL_TAP"TRUE";
"B \NAC \NWC"5;
"S \NAC"
BN"9"124;
%"TAP"
"1","(-5700,5075)","2","mstr_standard","I273";
;
CDS_LIB"mstr_standard"
BODY_TYPE"PLUMBING"
HDL_TAP"TRUE";
"B \NAC \NWC"5;
"S \NAC"
BN"8"122;
%"TAP"
"1","(-5900,5025)","2","mstr_standard","I274";
;
CDS_LIB"mstr_standard"
BODY_TYPE"PLUMBING"
HDL_TAP"TRUE";
"B \NAC \NWC"6;
"S \NAC"
BN"8"113;
%"TAP"
"1","(-5900,4925)","2","mstr_standard","I275";
;
CDS_LIB"mstr_standard"
BODY_TYPE"PLUMBING"
HDL_TAP"TRUE";
"B \NAC \NWC"6;
"S \NAC"
BN"9"115;
%"TAP"
"1","(-5700,4625)","2","mstr_standard","I276";
;
CDS_LIB"mstr_standard"
BODY_TYPE"PLUMBING"
HDL_TAP"TRUE";
"B \NAC \NWC"2;
"S \NAC"
BN"2"121;
%"TAP"
"1","(-5700,4825)","2","mstr_standard","I277";
;
CDS_LIB"mstr_standard"
BODY_TYPE"PLUMBING"
HDL_TAP"TRUE";
"B \NAC \NWC"2;
"S \NAC"
BN"0"117;
%"TAP"
"1","(-5700,4725)","2","mstr_standard","I278";
;
CDS_LIB"mstr_standard"
BODY_TYPE"PLUMBING"
HDL_TAP"TRUE";
"B \NAC \NWC"2;
"S \NAC"
BN"1"119;
%"TAP"
"1","(-5900,4675)","2","mstr_standard","I279";
;
CDS_LIB"mstr_standard"
BODY_TYPE"PLUMBING"
HDL_TAP"TRUE";
"B \NAC \NWC"3;
"S \NAC"
BN"1"111;
%"TAP"
"1","(-5900,4775)","2","mstr_standard","I280";
;
CDS_LIB"mstr_standard"
BODY_TYPE"PLUMBING"
HDL_TAP"TRUE";
"B \NAC \NWC"3;
"S \NAC"
BN"0"110;
%"TAP"
"1","(-5700,4525)","2","mstr_standard","I281";
;
CDS_LIB"mstr_standard"
BODY_TYPE"PLUMBING"
HDL_TAP"TRUE";
"B \NAC \NWC"2;
"S \NAC"
BN"3"123;
%"TAP"
"1","(-5700,4425)","2","mstr_standard","I282";
;
CDS_LIB"mstr_standard"
BODY_TYPE"PLUMBING"
HDL_TAP"TRUE";
"B \NAC \NWC"2;
"S \NAC"
BN"4"125;
%"TAP"
"1","(-5900,4575)","2","mstr_standard","I283";
;
CDS_LIB"mstr_standard"
BODY_TYPE"PLUMBING"
HDL_TAP"TRUE";
"B \NAC \NWC"3;
"S \NAC"
BN"2"112;
%"TAP"
"1","(-5900,4475)","2","mstr_standard","I284";
;
CDS_LIB"mstr_standard"
BODY_TYPE"PLUMBING"
HDL_TAP"TRUE";
"B \NAC \NWC"3;
"S \NAC"
BN"3"114;
%"TAP"
"1","(-5900,4375)","2","mstr_standard","I285";
;
CDS_LIB"mstr_standard"
BODY_TYPE"PLUMBING"
HDL_TAP"TRUE";
"B \NAC \NWC"3;
"S \NAC"
BN"4"116;
%"TAP"
"1","(-5700,4225)","2","mstr_standard","I286";
;
CDS_LIB"mstr_standard"
BODY_TYPE"PLUMBING"
HDL_TAP"TRUE";
"B \NAC \NWC"2;
"S \NAC"
BN"6"108;
%"TAP"
"1","(-5700,4125)","2","mstr_standard","I287";
;
CDS_LIB"mstr_standard"
BODY_TYPE"PLUMBING"
HDL_TAP"TRUE";
"B \NAC \NWC"2;
"S \NAC"
BN"7"109;
%"TAP"
"1","(-5700,4325)","2","mstr_standard","I288";
;
CDS_LIB"mstr_standard"
BODY_TYPE"PLUMBING"
HDL_TAP"TRUE";
"B \NAC \NWC"2;
"S \NAC"
BN"5"107;
%"TAP"
"1","(-5900,4175)","2","mstr_standard","I289";
;
CDS_LIB"mstr_standard"
BODY_TYPE"PLUMBING"
HDL_TAP"TRUE";
"B \NAC \NWC"3;
"S \NAC"
BN"6"120;
%"TAP"
"1","(-5900,4275)","2","mstr_standard","I290";
;
CDS_LIB"mstr_standard"
BODY_TYPE"PLUMBING"
HDL_TAP"TRUE";
"B \NAC \NWC"3;
"S \NAC"
BN"5"118;
%"TAP"
"1","(-5700,4025)","2","mstr_standard","I295";
;
CDS_LIB"mstr_standard"
BODY_TYPE"PLUMBING"
HDL_TAP"TRUE";
"B \NAC \NWC"2;
"S \NAC"
BN"8"127;
%"TAP"
"1","(-5700,3925)","2","mstr_standard","I296";
;
CDS_LIB"mstr_standard"
BODY_TYPE"PLUMBING"
HDL_TAP"TRUE";
"B \NAC \NWC"2;
"S \NAC"
BN"9"143;
%"TAP"
"1","(-5900,3875)","2","mstr_standard","I297";
;
CDS_LIB"mstr_standard"
BODY_TYPE"PLUMBING"
HDL_TAP"TRUE";
"B \NAC \NWC"3;
"S \NAC"
BN"9"126;
%"TAP"
"1","(-5900,3975)","2","mstr_standard","I298";
;
CDS_LIB"mstr_standard"
BODY_TYPE"PLUMBING"
HDL_TAP"TRUE";
"B \NAC \NWC"3;
"S \NAC"
BN"8"142;
%"TAP"
"1","(-5900,4075)","2","mstr_standard","I299";
;
CDS_LIB"mstr_standard"
BODY_TYPE"PLUMBING"
HDL_TAP"TRUE";
"B \NAC \NWC"3;
"S \NAC"
BN"7"141;
%"TAP"
"1","(-5900,3725)","2","mstr_standard","I300";
;
CDS_LIB"mstr_standard"
BODY_TYPE"PLUMBING"
HDL_TAP"TRUE";
"B \NAC \NWC"4;
"S \NAC"
BN"0"128;
%"TAP"
"1","(-5900,3675)","2","mstr_standard","I301";
;
CDS_LIB"mstr_standard"
BODY_TYPE"PLUMBING"
HDL_TAP"TRUE";
"B \NAC \NWC"4;
"S \NAC"
BN"1"130;
%"TAP"
"1","(-5900,3625)","2","mstr_standard","I302";
;
CDS_LIB"mstr_standard"
BODY_TYPE"PLUMBING"
HDL_TAP"TRUE";
"B \NAC \NWC"4;
"S \NAC"
BN"2"132;
%"TAP"
"1","(-5900,3525)","2","mstr_standard","I303";
;
CDS_LIB"mstr_standard"
BODY_TYPE"PLUMBING"
HDL_TAP"TRUE";
"B \NAC \NWC"4;
"S \NAC"
BN"4"136;
%"TAP"
"1","(-5900,3475)","2","mstr_standard","I304";
;
CDS_LIB"mstr_standard"
BODY_TYPE"PLUMBING"
HDL_TAP"TRUE";
"B \NAC \NWC"4;
"S \NAC"
BN"5"138;
%"TAP"
"1","(-5900,3575)","2","mstr_standard","I305";
;
CDS_LIB"mstr_standard"
BODY_TYPE"PLUMBING"
HDL_TAP"TRUE";
"B \NAC \NWC"4;
"S \NAC"
BN"3"134;
%"TAP"
"1","(-5900,3425)","2","mstr_standard","I306";
;
CDS_LIB"mstr_standard"
BODY_TYPE"PLUMBING"
HDL_TAP"TRUE";
"B \NAC \NWC"4;
"S \NAC"
BN"6"140;
%"TAP"
"1","(-5900,3325)","2","mstr_standard","I307";
;
CDS_LIB"mstr_standard"
BODY_TYPE"PLUMBING"
HDL_TAP"TRUE";
"B \NAC \NWC"1;
"S \NAC"
BN"0"129;
%"TAP"
"1","(-5900,3275)","2","mstr_standard","I308";
;
CDS_LIB"mstr_standard"
BODY_TYPE"PLUMBING"
HDL_TAP"TRUE";
"B \NAC \NWC"1;
"S \NAC"
BN"1"131;
%"TAP"
"1","(-5900,3225)","2","mstr_standard","I309";
;
CDS_LIB"mstr_standard"
BODY_TYPE"PLUMBING"
HDL_TAP"TRUE";
"B \NAC \NWC"1;
"S \NAC"
BN"2"133;
%"TAP"
"1","(-5900,3175)","2","mstr_standard","I310";
;
CDS_LIB"mstr_standard"
BODY_TYPE"PLUMBING"
HDL_TAP"TRUE";
"B \NAC \NWC"1;
"S \NAC"
BN"3"135;
%"TAP"
"1","(-5900,3125)","2","mstr_standard","I311";
;
CDS_LIB"mstr_standard"
BODY_TYPE"PLUMBING"
HDL_TAP"TRUE";
"B \NAC \NWC"1;
"S \NAC"
BN"4"137;
%"TAP"
"1","(-5900,3075)","2","mstr_standard","I312";
;
CDS_LIB"mstr_standard"
BODY_TYPE"PLUMBING"
HDL_TAP"TRUE";
"B \NAC \NWC"1;
"S \NAC"
BN"5"139;
%"TAP"
"1","(-5900,3025)","2","mstr_standard","I313";
;
CDS_LIB"mstr_standard"
BODY_TYPE"PLUMBING"
HDL_TAP"TRUE";
"B \NAC \NWC"1;
"S \NAC"
BN"6"144;
%"Q_RES"
"1","(-6825,2025)","0","pure_quanta","I327";
;
LOCATION"R376"
$SEC"1"
CDS_SEC"1"
PACK_TYPE"0402LF"
TOLERANCE"1%"
VALUE"15"
MATERIAL"CHIP"
WATTAGE"1/16W"
CDS_LIB"pure_quanta"
PART_NUMBER"CS01502FB03";
"B"
$PN"2"157;
"A"
$PN"1"156;
END.
